(kicad_pcb
	(version 20260206)
	(generator "pcbnew")
	(generator_version "10.0")
	(general
		(thickness 1.6)
		(legacy_teardrops no)
	)
	(paper "A4")
	(title_block
		(title "Bryce Canyon_F.DPB_16315-1-OCP.brd")
		(comment 1 "Bryce Canyon / footprint 448 of 2223 (MONO3), pads 1-73 of 166")
	)
	(layers
		(0 "F.Cu" signal "TOP")
		(4 "In1.Cu" signal "L2GND")
		(6 "In2.Cu" signal "L3")
		(8 "In3.Cu" signal "L4GND")
		(10 "In4.Cu" signal "L5")
		(12 "In5.Cu" signal "L6VCC")
		(14 "In6.Cu" signal "L7VCC")
		(16 "In7.Cu" signal "L8")
		(18 "In8.Cu" signal "L9GND")
		(20 "In9.Cu" signal "L10")
		(22 "In10.Cu" signal "L11GND")
		(2 "B.Cu" signal "BOTTOM")
		(9 "F.Adhes" user "F.Adhesive")
		(11 "B.Adhes" user "B.Adhesive")
		(13 "F.Paste" user "Package Geometry/Pastemask Top")
		(15 "B.Paste" user "Package Geometry/Pastemask Bottom")
		(5 "F.SilkS" user "Ref Des/Silkscreen Top")
		(7 "B.SilkS" user "Ref Des/Silkscreen Bottom")
		(1 "F.Mask" user "Board Geometry/Soldermask Top")
		(3 "B.Mask" user "Board Geometry/Soldermask Bottom")
		(17 "Dwgs.User" user "User.Drawings")
		(19 "Cmts.User" user "User.Comments")
		(21 "Eco1.User" user "User.Eco1")
		(23 "Eco2.User" user "User.Eco2")
		(25 "Edge.Cuts" user "Board Geometry/Outline")
		(27 "Margin" user)
		(31 "F.CrtYd" user "Package Geometry/Place Bound Top")
		(29 "B.CrtYd" user "Package Geometry/Place Bound Bottom")
		(35 "F.Fab" user "Ref Des/Assembly Top")
		(33 "B.Fab" user "Ref Des/Assembly Bottom")
	)
	(footprint ""
		(layer "F.Cu")
		(at 281.999944 -111.149892 90)
		(property "Reference" "MONO3"
			(at 0 0 90)
			(layer "F.SilkS")
			(hide yes)
			(effects
				(font
					(size 1.27 1.27)
				)
			)
		)
		(property "Value" "AMP-CONN164-4R-1-GP"
			(at -25.705054 -1.203706 90)
			(unlocked yes)
			(layer "F.Fab")
			(hide yes)
			(effects
				(font
					(size 1.016 1.016)
					(thickness 0.1524)
				)
			)
		)
		(property "Device Type" "PREFIT-164P-890091-1H441"
			(at -25.705054 -2.727706 90)
			(unlocked yes)
			(layer "F.Fab")
			(hide yes)
			(effects
				(font
					(size 1.016 1.016)
					(thickness 0.1524)
				)
			)
		)
		(duplicate_pad_numbers_are_jumpers no)
		(pad "" np_thru_hole circle
			(at 0 0 90)
			(size 0.254 0.254)
			(drill 2.3622)
			(layers "*.Cu" "*.Mask")
			(clearance 1.4097)
			(thermal_gap 1.4097)
		)
		(pad "" np_thru_hole circle
			(at 73.149968 0 90)
			(size 0.254 0.254)
			(drill 2.3622)
			(layers "*.Cu" "*.Mask")
			(clearance 1.4097)
			(thermal_gap 1.4097)
		)
		(pad "A1" thru_hole circle
			(at -11.649964 -1.249934 90)
			(size 1.0668 1.0668)
			(drill 0.719836)
			(layers "*.Cu" "*.Mask")
			(remove_unused_layers no)
			(net "COMP_B_PRI_INS_N")
			(clearance 0.1905)
			(thermal_gap 0.1905)
		)
		(pad "A2" thru_hole circle
			(at -10.649966 -3.24993 90)
			(size 1.0668 1.0668)
			(drill 0.719836)
			(layers "*.Cu" "*.Mask")
			(remove_unused_layers no)
			(net "P12V_B_COMP")
			(clearance 0.1905)
			(thermal_gap 0.1905)
		)
		(pad "A3" thru_hole circle
			(at -9.649968 -1.249934 90)
			(size 1.0668 1.0668)
			(drill 0.719836)
			(layers "*.Cu" "*.Mask")
			(remove_unused_layers no)
			(net "P12V_B_COMP")
			(clearance 0.1905)
			(thermal_gap 0.1905)
		)
		(pad "A4" thru_hole circle
			(at -8.64997 -3.24993 90)
			(size 1.0668 1.0668)
			(drill 0.719836)
			(layers "*.Cu" "*.Mask")
			(remove_unused_layers no)
			(net "GND")
			(clearance 0.1905)
			(thermal_gap 0.1905)
		)
		(pad "A5" thru_hole circle
			(at -7.649972 -1.249934 90)
			(size 1.0668 1.0668)
			(drill 0.719836)
			(layers "*.Cu" "*.Mask")
			(remove_unused_layers no)
			(net "SLOT1_SVR_ID0_GPIO0")
			(clearance 0.1905)
			(thermal_gap 0.1905)
		)
		(pad "A6" thru_hole circle
			(at -6.649974 -3.24993 90)
			(size 1.0668 1.0668)
			(drill 0.719836)
			(layers "*.Cu" "*.Mask")
			(remove_unused_layers no)
			(net "SLOT1_SVR_ID0_GPIO1")
			(clearance 0.1905)
			(thermal_gap 0.1905)
		)
		(pad "A7" thru_hole circle
			(at -5.649976 -1.249934 90)
			(size 1.0668 1.0668)
			(drill 0.719836)
			(layers "*.Cu" "*.Mask")
			(remove_unused_layers no)
			(net "UART_COMP_B_TX")
			(clearance 0.1905)
			(thermal_gap 0.1905)
		)
		(pad "A8" thru_hole circle
			(at -4.649978 -3.24993 90)
			(size 1.0668 1.0668)
			(drill 0.719836)
			(layers "*.Cu" "*.Mask")
			(remove_unused_layers no)
			(net "UART_COMP_B_RX")
			(clearance 0.1905)
			(thermal_gap 0.1905)
		)
		(pad "A9" thru_hole circle
			(at -3.64998 -1.249934 90)
			(size 1.0668 1.0668)
			(drill 0.719836)
			(layers "*.Cu" "*.Mask")
			(remove_unused_layers no)
			(net "SLOT1_SVR_ID0_GPIO2")
			(clearance 0.1905)
			(thermal_gap 0.1905)
		)
		(pad "A10" thru_hole circle
			(at -2.649982 -3.24993 90)
			(size 1.0668 1.0668)
			(drill 0.719836)
			(layers "*.Cu" "*.Mask")
			(remove_unused_layers no)
			(net "SLOT1_SVR_ID0_GPIO3")
			(clearance 0.1905)
			(thermal_gap 0.1905)
		)
		(pad "A11" thru_hole circle
			(at -1.649984 -1.249934 90)
			(size 1.0668 1.0668)
			(drill 0.719836)
			(layers "*.Cu" "*.Mask")
			(remove_unused_layers no)
			(net "PCIE_COMP_B_TO_SCC_B_RST_0")
			(clearance 0.1905)
			(thermal_gap 0.1905)
		)
		(pad "A12" thru_hole circle
			(at 1.35001 -3.24993 90)
			(size 1.0668 1.0668)
			(drill 0.719836)
			(layers "*.Cu" "*.Mask")
			(remove_unused_layers no)
			(net "GND")
			(clearance 0.1905)
			(thermal_gap 0.1905)
		)
		(pad "A13" thru_hole circle
			(at 2.350008 -1.249934 90)
			(size 1.0668 1.0668)
			(drill 0.719836)
			(layers "*.Cu" "*.Mask")
			(remove_unused_layers no)
			(net "PCIE_COMP_B_TO_SCC_B_CLK_0_DP")
			(clearance 0.1905)
			(thermal_gap 0.1905)
		)
		(pad "A14" thru_hole circle
			(at 3.350006 -3.24993 90)
			(size 1.0668 1.0668)
			(drill 0.719836)
			(layers "*.Cu" "*.Mask")
			(remove_unused_layers no)
			(net "PCIE_COMP_B_TO_SCC_B_CLK_0_DN")
			(clearance 0.1905)
			(thermal_gap 0.1905)
		)
		(pad "A15" thru_hole circle
			(at 4.350004 -1.249934 90)
			(size 1.0668 1.0668)
			(drill 0.719836)
			(layers "*.Cu" "*.Mask")
			(remove_unused_layers no)
			(net "GND")
			(clearance 0.1905)
			(thermal_gap 0.1905)
		)
		(pad "A16" thru_hole circle
			(at 5.350002 -3.24993 90)
			(size 1.0668 1.0668)
			(drill 0.719836)
			(layers "*.Cu" "*.Mask")
			(remove_unused_layers no)
			(net "GND")
			(clearance 0.1905)
			(thermal_gap 0.1905)
		)
		(pad "A17" thru_hole circle
			(at 6.35 -1.249934 90)
			(size 1.0668 1.0668)
			(drill 0.719836)
			(layers "*.Cu" "*.Mask")
			(remove_unused_layers no)
			(net "PCIE_SCC_B_TO_COMP_B_0_DP")
			(clearance 0.1905)
			(thermal_gap 0.1905)
		)
		(pad "A18" thru_hole circle
			(at 7.349998 -3.24993 90)
			(size 1.0668 1.0668)
			(drill 0.719836)
			(layers "*.Cu" "*.Mask")
			(remove_unused_layers no)
			(net "PCIE_SCC_B_TO_COMP_B_0_DN")
			(clearance 0.1905)
			(thermal_gap 0.1905)
		)
		(pad "A19" thru_hole circle
			(at 8.349996 -1.249934 90)
			(size 1.0668 1.0668)
			(drill 0.719836)
			(layers "*.Cu" "*.Mask")
			(remove_unused_layers no)
			(net "GND")
			(clearance 0.1905)
			(thermal_gap 0.1905)
		)
		(pad "A20" thru_hole circle
			(at 9.349994 -3.24993 90)
			(size 1.0668 1.0668)
			(drill 0.719836)
			(layers "*.Cu" "*.Mask")
			(remove_unused_layers no)
			(net "GND")
			(clearance 0.1905)
			(thermal_gap 0.1905)
		)
		(pad "A21" thru_hole circle
			(at 10.349992 -1.249934 90)
			(size 1.0668 1.0668)
			(drill 0.719836)
			(layers "*.Cu" "*.Mask")
			(remove_unused_layers no)
			(net "PCIE_SCC_B_TO_COMP_B_1_DP")
			(clearance 0.1905)
			(thermal_gap 0.1905)
		)
		(pad "A22" thru_hole circle
			(at 11.34999 -3.24993 90)
			(size 1.0668 1.0668)
			(drill 0.719836)
			(layers "*.Cu" "*.Mask")
			(remove_unused_layers no)
			(net "PCIE_SCC_B_TO_COMP_B_1_DN")
			(clearance 0.1905)
			(thermal_gap 0.1905)
		)
		(pad "A23" thru_hole circle
			(at 12.349988 -1.249934 90)
			(size 1.0668 1.0668)
			(drill 0.719836)
			(layers "*.Cu" "*.Mask")
			(remove_unused_layers no)
			(net "GND")
			(clearance 0.1905)
			(thermal_gap 0.1905)
		)
		(pad "A24" thru_hole circle
			(at 13.349986 -3.24993 90)
			(size 1.0668 1.0668)
			(drill 0.719836)
			(layers "*.Cu" "*.Mask")
			(remove_unused_layers no)
			(net "GND")
			(clearance 0.1905)
			(thermal_gap 0.1905)
		)
		(pad "A25" thru_hole circle
			(at 14.349984 -1.249934 90)
			(size 1.0668 1.0668)
			(drill 0.719836)
			(layers "*.Cu" "*.Mask")
			(remove_unused_layers no)
			(net "PCIE_SCC_B_TO_COMP_B_2_DP")
			(clearance 0.1905)
			(thermal_gap 0.1905)
		)
		(pad "A26" thru_hole circle
			(at 15.349982 -3.24993 90)
			(size 1.0668 1.0668)
			(drill 0.719836)
			(layers "*.Cu" "*.Mask")
			(remove_unused_layers no)
			(net "PCIE_SCC_B_TO_COMP_B_2_DN")
			(clearance 0.1905)
			(thermal_gap 0.1905)
		)
		(pad "A27" thru_hole circle
			(at 16.34998 -1.249934 90)
			(size 1.0668 1.0668)
			(drill 0.719836)
			(layers "*.Cu" "*.Mask")
			(remove_unused_layers no)
			(net "GND")
			(clearance 0.1905)
			(thermal_gap 0.1905)
		)
		(pad "A28" thru_hole circle
			(at 17.349978 -3.24993 90)
			(size 1.0668 1.0668)
			(drill 0.719836)
			(layers "*.Cu" "*.Mask")
			(remove_unused_layers no)
			(net "GND")
			(clearance 0.1905)
			(thermal_gap 0.1905)
		)
		(pad "A29" thru_hole circle
			(at 18.349976 -1.249934 90)
			(size 1.0668 1.0668)
			(drill 0.719836)
			(layers "*.Cu" "*.Mask")
			(remove_unused_layers no)
			(net "PCIE_SCC_B_TO_COMP_B_3_DP")
			(clearance 0.1905)
			(thermal_gap 0.1905)
		)
		(pad "A30" thru_hole circle
			(at 19.349974 -3.24993 90)
			(size 1.0668 1.0668)
			(drill 0.719836)
			(layers "*.Cu" "*.Mask")
			(remove_unused_layers no)
			(net "PCIE_SCC_B_TO_COMP_B_3_DN")
			(clearance 0.1905)
			(thermal_gap 0.1905)
		)
		(pad "A31" thru_hole circle
			(at 20.349972 -1.249934 90)
			(size 1.0668 1.0668)
			(drill 0.719836)
			(layers "*.Cu" "*.Mask")
			(remove_unused_layers no)
			(net "GND")
			(clearance 0.1905)
			(thermal_gap 0.1905)
		)
		(pad "A32" thru_hole circle
			(at 21.34997 -3.24993 90)
			(size 1.0668 1.0668)
			(drill 0.719836)
			(layers "*.Cu" "*.Mask")
			(remove_unused_layers no)
			(net "GND")
			(clearance 0.1905)
			(thermal_gap 0.1905)
		)
		(pad "A33" thru_hole circle
			(at 22.349968 -1.249934 90)
			(size 1.0668 1.0668)
			(drill 0.719836)
			(layers "*.Cu" "*.Mask")
			(remove_unused_layers no)
			(net "TP_COMP_B_SATA_P0_RX_DP")
			(clearance 0.1905)
			(thermal_gap 0.1905)
		)
		(pad "A34" thru_hole circle
			(at 23.349966 -3.24993 90)
			(size 1.0668 1.0668)
			(drill 0.719836)
			(layers "*.Cu" "*.Mask")
			(remove_unused_layers no)
			(net "TP_COMP_B_SATA_P0_RX_DN")
			(clearance 0.1905)
			(thermal_gap 0.1905)
		)
		(pad "A35" thru_hole circle
			(at 24.349964 -1.249934 90)
			(size 1.0668 1.0668)
			(drill 0.719836)
			(layers "*.Cu" "*.Mask")
			(remove_unused_layers no)
			(net "GND")
			(clearance 0.1905)
			(thermal_gap 0.1905)
		)
		(pad "A36" thru_hole circle
			(at 25.349962 -3.24993 90)
			(size 1.0668 1.0668)
			(drill 0.719836)
			(layers "*.Cu" "*.Mask")
			(remove_unused_layers no)
			(net "GND")
			(clearance 0.1905)
			(thermal_gap 0.1905)
		)
		(pad "A37" thru_hole circle
			(at 26.34996 -1.249934 90)
			(size 1.0668 1.0668)
			(drill 0.719836)
			(layers "*.Cu" "*.Mask")
			(remove_unused_layers no)
			(net "PCIE_COMP_B_TO_IOM_B_CLK_2_DP")
			(clearance 0.1905)
			(thermal_gap 0.1905)
		)
		(pad "A38" thru_hole circle
			(at 27.349958 -3.24993 90)
			(size 1.0668 1.0668)
			(drill 0.719836)
			(layers "*.Cu" "*.Mask")
			(remove_unused_layers no)
			(net "PCIE_COMP_B_TO_IOM_B_CLK_2_DN")
			(clearance 0.1905)
			(thermal_gap 0.1905)
		)
		(pad "A39" thru_hole circle
			(at 28.349956 -1.249934 90)
			(size 1.0668 1.0668)
			(drill 0.719836)
			(layers "*.Cu" "*.Mask")
			(remove_unused_layers no)
			(net "GND")
			(clearance 0.1905)
			(thermal_gap 0.1905)
		)
		(pad "A40" thru_hole circle
			(at 29.349954 -3.24993 90)
			(size 1.0668 1.0668)
			(drill 0.719836)
			(layers "*.Cu" "*.Mask")
			(remove_unused_layers no)
			(net "GND")
			(clearance 0.1905)
			(thermal_gap 0.1905)
		)
		(pad "A41" thru_hole circle
			(at 30.349952 -1.249934 90)
			(size 1.0668 1.0668)
			(drill 0.719836)
			(layers "*.Cu" "*.Mask")
			(remove_unused_layers no)
			(net "COMP_B_FAST_THROTTLE_N")
			(clearance 0.1905)
			(thermal_gap 0.1905)
		)
		(pad "A42" thru_hole circle
			(at 31.34995 -3.24993 90)
			(size 1.0668 1.0668)
			(drill 0.719836)
			(layers "*.Cu" "*.Mask")
			(remove_unused_layers no)
			(net "TP_SMB_COMP_B_NIC_ALERT_N")
			(clearance 0.1905)
			(thermal_gap 0.1905)
		)
		(pad "A43" thru_hole circle
			(at 32.349948 -1.249934 90)
			(size 1.0668 1.0668)
			(drill 0.719836)
			(layers "*.Cu" "*.Mask")
			(remove_unused_layers no)
			(net "GND")
			(clearance 0.1905)
			(thermal_gap 0.1905)
		)
		(pad "A44" thru_hole circle
			(at 33.349946 -3.24993 90)
			(size 1.0668 1.0668)
			(drill 0.719836)
			(layers "*.Cu" "*.Mask")
			(remove_unused_layers no)
			(net "GND")
			(clearance 0.1905)
			(thermal_gap 0.1905)
		)
		(pad "A45" thru_hole circle
			(at 34.349944 -1.249934 90)
			(size 1.0668 1.0668)
			(drill 0.719836)
			(layers "*.Cu" "*.Mask")
			(remove_unused_layers no)
			(net "TP_COMP_B_KR_P0_RX_DP")
			(clearance 0.1905)
			(thermal_gap 0.1905)
		)
		(pad "A46" thru_hole circle
			(at 35.349942 -3.24993 90)
			(size 1.0668 1.0668)
			(drill 0.719836)
			(layers "*.Cu" "*.Mask")
			(remove_unused_layers no)
			(net "TP_COMP_B_KR_P0_RX_DN")
			(clearance 0.1905)
			(thermal_gap 0.1905)
		)
		(pad "A47" thru_hole circle
			(at 36.34994 -1.249934 90)
			(size 1.0668 1.0668)
			(drill 0.719836)
			(layers "*.Cu" "*.Mask")
			(remove_unused_layers no)
			(net "GND")
			(clearance 0.1905)
			(thermal_gap 0.1905)
		)
		(pad "A48" thru_hole circle
			(at 37.349938 -3.24993 90)
			(size 1.0668 1.0668)
			(drill 0.719836)
			(layers "*.Cu" "*.Mask")
			(remove_unused_layers no)
			(net "GND")
			(clearance 0.1905)
			(thermal_gap 0.1905)
		)
		(pad "A49" thru_hole circle
			(at 38.349936 -1.249934 90)
			(size 1.0668 1.0668)
			(drill 0.719836)
			(layers "*.Cu" "*.Mask")
			(remove_unused_layers no)
			(net "PCIE_SCC_B_TO_COMP_B_4_DP")
			(clearance 0.1905)
			(thermal_gap 0.1905)
		)
		(pad "A50" thru_hole circle
			(at 39.349934 -3.24993 90)
			(size 1.0668 1.0668)
			(drill 0.719836)
			(layers "*.Cu" "*.Mask")
			(remove_unused_layers no)
			(net "PCIE_SCC_B_TO_COMP_B_4_DN")
			(clearance 0.1905)
			(thermal_gap 0.1905)
		)
		(pad "A51" thru_hole circle
			(at 40.349932 -1.249934 90)
			(size 1.0668 1.0668)
			(drill 0.719836)
			(layers "*.Cu" "*.Mask")
			(remove_unused_layers no)
			(net "GND")
			(clearance 0.1905)
			(thermal_gap 0.1905)
		)
		(pad "A52" thru_hole circle
			(at 41.34993 -3.24993 90)
			(size 1.0668 1.0668)
			(drill 0.719836)
			(layers "*.Cu" "*.Mask")
			(remove_unused_layers no)
			(net "GND")
			(clearance 0.1905)
			(thermal_gap 0.1905)
		)
		(pad "A53" thru_hole circle
			(at 42.349928 -1.249934 90)
			(size 1.0668 1.0668)
			(drill 0.719836)
			(layers "*.Cu" "*.Mask")
			(remove_unused_layers no)
			(net "PCIE_SCC_B_TO_COMP_B_5_DP")
			(clearance 0.1905)
			(thermal_gap 0.1905)
		)
		(pad "A54" thru_hole circle
			(at 43.349926 -3.24993 90)
			(size 1.0668 1.0668)
			(drill 0.719836)
			(layers "*.Cu" "*.Mask")
			(remove_unused_layers no)
			(net "PCIE_SCC_B_TO_COMP_B_5_DN")
			(clearance 0.1905)
			(thermal_gap 0.1905)
		)
		(pad "A55" thru_hole circle
			(at 44.349924 -1.249934 90)
			(size 1.0668 1.0668)
			(drill 0.719836)
			(layers "*.Cu" "*.Mask")
			(remove_unused_layers no)
			(net "GND")
			(clearance 0.1905)
			(thermal_gap 0.1905)
		)
		(pad "A56" thru_hole circle
			(at 45.349922 -3.24993 90)
			(size 1.0668 1.0668)
			(drill 0.719836)
			(layers "*.Cu" "*.Mask")
			(remove_unused_layers no)
			(net "GND")
			(clearance 0.1905)
			(thermal_gap 0.1905)
		)
		(pad "A57" thru_hole circle
			(at 46.34992 -1.249934 90)
			(size 1.0668 1.0668)
			(drill 0.719836)
			(layers "*.Cu" "*.Mask")
			(remove_unused_layers no)
			(net "PCIE_SCC_B_TO_COMP_B_6_DP")
			(clearance 0.1905)
			(thermal_gap 0.1905)
		)
		(pad "A58" thru_hole circle
			(at 47.349918 -3.24993 90)
			(size 1.0668 1.0668)
			(drill 0.719836)
			(layers "*.Cu" "*.Mask")
			(remove_unused_layers no)
			(net "PCIE_SCC_B_TO_COMP_B_6_DN")
			(clearance 0.1905)
			(thermal_gap 0.1905)
		)
		(pad "A59" thru_hole circle
			(at 48.349916 -1.249934 90)
			(size 1.0668 1.0668)
			(drill 0.719836)
			(layers "*.Cu" "*.Mask")
			(remove_unused_layers no)
			(net "GND")
			(clearance 0.1905)
			(thermal_gap 0.1905)
		)
		(pad "A60" thru_hole circle
			(at 49.349914 -3.24993 90)
			(size 1.0668 1.0668)
			(drill 0.719836)
			(layers "*.Cu" "*.Mask")
			(remove_unused_layers no)
			(net "GND")
			(clearance 0.1905)
			(thermal_gap 0.1905)
		)
		(pad "A61" thru_hole circle
			(at 50.349912 -1.249934 90)
			(size 1.0668 1.0668)
			(drill 0.719836)
			(layers "*.Cu" "*.Mask")
			(remove_unused_layers no)
			(net "PCIE_SCC_B_TO_COMP_B_7_DP")
			(clearance 0.1905)
			(thermal_gap 0.1905)
		)
		(pad "A62" thru_hole circle
			(at 51.34991 -3.24993 90)
			(size 1.0668 1.0668)
			(drill 0.719836)
			(layers "*.Cu" "*.Mask")
			(remove_unused_layers no)
			(net "PCIE_SCC_B_TO_COMP_B_7_DN")
			(clearance 0.1905)
			(thermal_gap 0.1905)
		)
		(pad "A63" thru_hole circle
			(at 52.349908 -1.249934 90)
			(size 1.0668 1.0668)
			(drill 0.719836)
			(layers "*.Cu" "*.Mask")
			(remove_unused_layers no)
			(net "GND")
			(clearance 0.1905)
			(thermal_gap 0.1905)
		)
		(pad "A64" thru_hole circle
			(at 53.349906 -3.24993 90)
			(size 1.0668 1.0668)
			(drill 0.719836)
			(layers "*.Cu" "*.Mask")
			(remove_unused_layers no)
			(net "GND")
			(clearance 0.1905)
			(thermal_gap 0.1905)
		)
		(pad "A65" thru_hole circle
			(at 54.349904 -1.249934 90)
			(size 1.0668 1.0668)
			(drill 0.719836)
			(layers "*.Cu" "*.Mask")
			(remove_unused_layers no)
			(net "PCIE_IOM_B_TO_COMP_B_8_DP")
			(clearance 0.1905)
			(thermal_gap 0.1905)
		)
		(pad "A66" thru_hole circle
			(at 55.349902 -3.24993 90)
			(size 1.0668 1.0668)
			(drill 0.719836)
			(layers "*.Cu" "*.Mask")
			(remove_unused_layers no)
			(net "PCIE_IOM_B_TO_COMP_B_8_DN")
			(clearance 0.1905)
			(thermal_gap 0.1905)
		)
		(pad "A67" thru_hole circle
			(at 56.3499 -1.249934 90)
			(size 1.0668 1.0668)
			(drill 0.719836)
			(layers "*.Cu" "*.Mask")
			(remove_unused_layers no)
			(net "GND")
			(clearance 0.1905)
			(thermal_gap 0.1905)
		)
		(pad "A68" thru_hole circle
			(at 57.349898 -3.24993 90)
			(size 1.0668 1.0668)
			(drill 0.719836)
			(layers "*.Cu" "*.Mask")
			(remove_unused_layers no)
			(net "GND")
			(clearance 0.1905)
			(thermal_gap 0.1905)
		)
		(pad "A69" thru_hole circle
			(at 58.349896 -1.249934 90)
			(size 1.0668 1.0668)
			(drill 0.719836)
			(layers "*.Cu" "*.Mask")
			(remove_unused_layers no)
			(net "PCIE_IOM_B_TO_COMP_B_9_DP")
			(clearance 0.1905)
			(thermal_gap 0.1905)
		)
		(pad "A70" thru_hole circle
			(at 59.349894 -3.24993 90)
			(size 1.0668 1.0668)
			(drill 0.719836)
			(layers "*.Cu" "*.Mask")
			(remove_unused_layers no)
			(net "PCIE_IOM_B_TO_COMP_B_9_DN")
			(clearance 0.1905)
			(thermal_gap 0.1905)
		)
		(pad "A71" thru_hole circle
			(at 60.349892 -1.249934 90)
			(size 1.0668 1.0668)
			(drill 0.719836)
			(layers "*.Cu" "*.Mask")
			(remove_unused_layers no)
			(net "GND")
			(clearance 0.1905)
			(thermal_gap 0.1905)
		)
	)
)
